(kicad_pcb
	(version 20260206)
	(generator "pcbnew")
	(generator_version "10.0")
	(general
		(thickness 1.6)
		(legacy_teardrops no)
	)
	(paper "A4")
	(title_block
		(title "netronome-mezz — pcbd0082-001_rev01_jul9_a.brd")
		(comment 1 "Open CloudServer (Microsoft) / footprints 47-52 of 714")
	)
	(layers
		(0 "F.Cu" signal "TOP")
		(4 "In1.Cu" signal "02_GND")
		(6 "In2.Cu" signal "03_SIG")
		(8 "In3.Cu" signal "04_SIG")
		(10 "In4.Cu" signal "05_GND")
		(12 "In5.Cu" signal "06_PWR1")
		(14 "In6.Cu" signal "07_SIG")
		(16 "In7.Cu" signal "08_SIG")
		(18 "In8.Cu" signal "09_GND")
		(2 "B.Cu" signal "BOTTOM")
		(9 "F.Adhes" user "F.Adhesive")
		(11 "B.Adhes" user "B.Adhesive")
		(13 "F.Paste" user "Package Geometry/Pastemask Top")
		(15 "B.Paste" user "Package Geometry/Pastemask Bottom")
		(5 "F.SilkS" user "Ref Des/Silkscreen Top")
		(7 "B.SilkS" user "Ref Des/Silkscreen Bottom")
		(1 "F.Mask" user "Board Geometry/Soldermask Top")
		(3 "B.Mask" user "Board Geometry/Soldermask Bottom")
		(17 "Dwgs.User" user "User.Drawings")
		(19 "Cmts.User" user "User.Comments")
		(21 "Eco1.User" user "User.Eco1")
		(23 "Eco2.User" user "User.Eco2")
		(25 "Edge.Cuts" user "Board Geometry/Outline")
		(27 "Margin" user)
		(31 "F.CrtYd" user "Package Geometry/Place Bound Top")
		(29 "B.CrtYd" user "Package Geometry/Place Bound Bottom")
		(35 "F.Fab" user "Ref Des/Assembly Top")
		(33 "B.Fab" user "Ref Des/Assembly Bottom")
		(45 "User.4" user "COMPVAL_TYPE_BOTTOM")
	)
	(footprint ""
		(layer "F.Cu")
		(at 63.5 49.784 90)
		(property "Reference" "U13"
			(at -2.43967 -2.032 0)
			(unlocked yes)
			(layer "F.SilkS")
			(effects
				(font
					(size 0.7874 0.5842)
					(thickness 0.127)
				)
				(justify left)
			)
		)
		(property "Value" "VAL"
			(at 0 2.010918 90)
			(unlocked yes)
			(layer "F.Fab")
			(hide yes)
			(effects
				(font
					(size 1.27 0.964946)
					(thickness 0.000001)
				)
			)
		)
		(property "Tolerance" "TOL"
			(at 0 3.915918 90)
			(unlocked yes)
			(layer "Cmts.User")
			(hide yes)
			(effects
				(font
					(size 1.27 0.964946)
					(thickness 0.000001)
				)
			)
		)
		(property "User Part Number" "PN"
			(at 0 -3.704082 90)
			(unlocked yes)
			(layer "Cmts.User")
			(hide yes)
			(effects
				(font
					(size 1.27 0.964946)
					(thickness 0.000001)
				)
			)
		)
		(property "Device Type" "DCDC0066"
			(at 0 -1.799082 90)
			(unlocked yes)
			(layer "F.Fab")
			(hide yes)
			(effects
				(font
					(size 1.27 0.964946)
					(thickness 0.000001)
				)
			)
		)
		(duplicate_pad_numbers_are_jumpers no)
		(fp_line
			(start 1.601216 -1.601216)
			(end 1.601216 -1.169162)
			(stroke
				(width 0.1524)
				(type default)
			)
			(layer "F.SilkS")
		)
		(fp_line
			(start 1.169162 -1.601216)
			(end 1.601216 -1.601216)
			(stroke
				(width 0.1524)
				(type default)
			)
			(layer "F.SilkS")
		)
		(fp_line
			(start -1.220216 -1.601216)
			(end -1.169162 -1.601216)
			(stroke
				(width 0.1524)
				(type default)
			)
			(layer "F.SilkS")
		)
		(fp_line
			(start -1.601216 -1.220216)
			(end -1.220216 -1.601216)
			(stroke
				(width 0.1524)
				(type default)
			)
			(layer "F.SilkS")
		)
		(fp_line
			(start -1.601216 -1.169162)
			(end -1.601216 -1.220216)
			(stroke
				(width 0.1524)
				(type default)
			)
			(layer "F.SilkS")
		)
		(fp_line
			(start 1.601216 1.169162)
			(end 1.601216 1.601216)
			(stroke
				(width 0.1524)
				(type default)
			)
			(layer "F.SilkS")
		)
		(fp_line
			(start 1.601216 1.601216)
			(end 1.169162 1.601216)
			(stroke
				(width 0.1524)
				(type default)
			)
			(layer "F.SilkS")
		)
		(fp_line
			(start -1.169162 1.601216)
			(end -1.601216 1.601216)
			(stroke
				(width 0.1524)
				(type default)
			)
			(layer "F.SilkS")
		)
		(fp_line
			(start -1.601216 1.601216)
			(end -1.601216 1.169162)
			(stroke
				(width 0.1524)
				(type default)
			)
			(layer "F.SilkS")
		)
		(fp_arc
			(start -1.677492 -1.893037)
			(mid -1.497852 -1.818614)
			(end -1.423416 -1.63896)
			(stroke
				(width 0.1524)
				(type default)
			)
			(layer "F.SilkS")
		)
		(fp_arc
			(start -1.832153 -1.840535)
			(mid -1.759157 -1.879554)
			(end -1.677492 -1.893037)
			(stroke
				(width 0.1524)
				(type default)
			)
			(layer "F.SilkS")
		)
		(fp_arc
			(start -1.423416 -1.63896)
			(mid -1.497847 -1.459324)
			(end -1.677492 -1.384884)
			(stroke
				(width 0.1524)
				(type default)
			)
			(layer "F.SilkS")
		)
		(fp_arc
			(start -1.677492 -1.384884)
			(mid -1.802412 -1.41776)
			(end -1.895043 -1.507795)
			(stroke
				(width 0.1524)
				(type default)
			)
			(layer "F.SilkS")
		)
		(fp_circle
			(center -1.677492 -1.63896)
			(end -1.677492 -1.384884)
			(stroke
				(width 0.1524)
				(type default)
			)
			(fill no)
			(layer "F.SilkS")
		)
		(fp_poly
			(pts
				(xy -1.91897 -1.91897) (xy -1.91897 1.91897) (xy 1.91897 1.91897) (xy 1.91897 -1.91897)
			)
			(stroke
				(width 0)
				(type default)
			)
			(fill no)
			(layer "F.CrtYd")
		)
		(fp_line
			(start 1.525016 -1.525016)
			(end -1.144016 -1.525016)
			(stroke
				(width 0.0254)
				(type default)
			)
			(layer "F.Fab")
		)
		(fp_line
			(start -1.144016 -1.525016)
			(end -1.525016 -1.144016)
			(stroke
				(width 0.0254)
				(type default)
			)
			(layer "F.Fab")
		)
		(fp_line
			(start -1.525016 -1.144016)
			(end -1.525016 1.525016)
			(stroke
				(width 0.0254)
				(type default)
			)
			(layer "F.Fab")
		)
		(fp_line
			(start 1.525016 1.525016)
			(end 1.525016 -1.525016)
			(stroke
				(width 0.0254)
				(type default)
			)
			(layer "F.Fab")
		)
		(fp_line
			(start -1.525016 1.525016)
			(end 1.525016 1.525016)
			(stroke
				(width 0.0254)
				(type default)
			)
			(layer "F.Fab")
		)
		(fp_circle
			(center -1.046734 -0.74996)
			(end -1.046734 -0.49596)
			(stroke
				(width 0.0254)
				(type default)
			)
			(fill no)
			(layer "F.Fab")
		)
		(pad "1" smd rect
			(at -1.359916 -0.750062)
			(size 0.279908 0.483108)
			(layers "F.Cu" "F.Mask" "F.Paste")
			(net "11N1952")
		)
		(pad "2" smd rect
			(at -1.359916 -0.249936)
			(size 0.279908 0.483108)
			(layers "F.Cu" "F.Mask" "F.Paste")
			(net "EXT_12.0V")
		)
		(pad "3" smd rect
			(at -1.359916 0.249936)
			(size 0.279908 0.483108)
			(layers "F.Cu" "F.Mask" "F.Paste")
			(net "EXT_12.0V")
		)
		(pad "4" smd rect
			(at -1.359916 0.750062)
			(size 0.279908 0.483108)
			(layers "F.Cu" "F.Mask" "F.Paste")
			(net "GND")
		)
		(pad "5" smd rect
			(at -0.750062 1.359916 90)
			(size 0.279908 0.483108)
			(layers "F.Cu" "F.Mask" "F.Paste")
			(net "11N1953")
		)
		(pad "6" smd rect
			(at -0.249936 1.359916 90)
			(size 0.279908 0.483108)
			(layers "F.Cu" "F.Mask" "F.Paste")
			(net "_NC_MIC24085_NC1")
		)
		(pad "7" smd rect
			(at 0.249936 1.359916 90)
			(size 0.279908 0.483108)
			(layers "F.Cu" "F.Mask" "F.Paste")
			(net "_NC_MIC24085_NC2")
		)
		(pad "8" smd rect
			(at 0.750062 1.359916 90)
			(size 0.279908 0.483108)
			(layers "F.Cu" "F.Mask" "F.Paste")
			(net "VDD_5.0V_PGOOD")
		)
		(pad "9" smd rect
			(at 1.359916 0.750062)
			(size 0.279908 0.483108)
			(layers "F.Cu" "F.Mask" "F.Paste")
			(net "VDD_5.0V_EN")
		)
		(pad "10" smd rect
			(at 1.359916 0.249936)
			(size 0.279908 0.483108)
			(layers "F.Cu" "F.Mask" "F.Paste")
			(net "11N1981")
		)
		(pad "11" smd rect
			(at 1.359916 -0.249936)
			(size 0.279908 0.483108)
			(layers "F.Cu" "F.Mask" "F.Paste")
			(net "EXT_12.0V")
		)
		(pad "12" smd rect
			(at 1.359916 -0.750062)
			(size 0.279908 0.483108)
			(layers "F.Cu" "F.Mask" "F.Paste")
			(net "11N1952")
		)
		(pad "13" smd rect
			(at 0.750062 -1.359916 90)
			(size 0.279908 0.483108)
			(layers "F.Cu" "F.Mask" "F.Paste")
			(net "11N1952")
		)
		(pad "14" smd rect
			(at 0.249936 -1.359916 90)
			(size 0.279908 0.483108)
			(layers "F.Cu" "F.Mask" "F.Paste")
			(net "GND")
		)
		(pad "15" smd rect
			(at -0.249936 -1.359916 90)
			(size 0.279908 0.483108)
			(layers "F.Cu" "F.Mask" "F.Paste")
			(net "GND")
		)
		(pad "16" smd rect
			(at -0.750062 -1.359916 90)
			(size 0.279908 0.483108)
			(layers "F.Cu" "F.Mask" "F.Paste")
			(net "11N1952")
		)
		(pad "17" smd rect
			(at 0 0 90)
			(size 1.700022 1.700022)
			(layers "F.Cu" "F.Mask" "F.Paste")
			(net "GND")
		)
	)
	(footprint ""
		(layer "F.Cu")
		(at 19.304 5.207 -90)
		(property "Reference" "R372"
			(at 0 0 270)
			(layer "F.SilkS")
			(hide yes)
			(effects
				(font
					(size 1.27 1.27)
				)
			)
		)
		(property "Value" "4.75K"
			(at -0.148158 1.3462 0)
			(unlocked yes)
			(layer "F.Fab")
			(hide yes)
			(effects
				(font
					(size 1.27 0.9652)
					(thickness 0.000001)
				)
				(justify left)
			)
		)
		(property "Device Type" "REST4024"
			(at -0.148158 1.3462 0)
			(unlocked yes)
			(layer "F.Fab")
			(hide yes)
			(effects
				(font
					(size 1.27 0.9652)
					(thickness 0.000001)
				)
				(justify left)
			)
		)
		(duplicate_pad_numbers_are_jumpers no)
		(fp_poly
			(pts
				(xy 0.635 1.0668) (xy 0.635 -1.0668) (xy -0.635 -1.0668) (xy -0.635 1.0668)
			)
			(stroke
				(width 0)
				(type default)
			)
			(fill no)
			(layer "F.CrtYd")
		)
		(fp_line
			(start -0.254 0.508)
			(end -0.254 -0.508)
			(stroke
				(width 0.0254)
				(type default)
			)
			(layer "F.Fab")
		)
		(fp_line
			(start 0.254 0.508)
			(end -0.254 0.508)
			(stroke
				(width 0.0254)
				(type default)
			)
			(layer "F.Fab")
		)
		(fp_line
			(start -0.254 -0.508)
			(end 0.254 -0.508)
			(stroke
				(width 0.0254)
				(type default)
			)
			(layer "F.Fab")
		)
		(fp_line
			(start 0.254 -0.508)
			(end 0.254 0.508)
			(stroke
				(width 0.0254)
				(type default)
			)
			(layer "F.Fab")
		)
		(pad "1" smd rect
			(at 0 -0.4191 270)
			(size 0.508 0.5334)
			(layers "F.Cu" "F.Mask" "F.Paste")
			(net "13N4321")
		)
		(pad "2" smd rect
			(at 0 0.4191 270)
			(size 0.508 0.5334)
			(layers "F.Cu" "F.Mask" "F.Paste")
			(net "GND")
		)
		(zone
			(layer "F.Cu")
			(hatch none 0.5)
			(connect_pads
				(clearance 0)
			)
			(min_thickness 0.25)
			(keepout
				(tracks not_allowed)
				(vias allowed)
				(pads allowed)
				(copperpour not_allowed)
				(footprints allowed)
			)
			(placement
				(enabled no)
				(sheetname "")
			)
			(fill
				(thermal_gap 0.5)
				(thermal_bridge_width 0.5)
				(island_removal_mode 0)
			)
			(polygon
				(pts
					(xy 19.3294 5.2324) (xy 19.2786 5.2324) (xy 19.2786 5.1816) (xy 19.3294 5.1816)
				)
			)
		)
	)
	(footprint ""
		(layer "F.Cu")
		(at 76.708 28.194 -90)
		(property "Reference" "R8"
			(at -0.73533 1.143 0)
			(unlocked yes)
			(layer "F.SilkS")
			(effects
				(font
					(size 0.7874 0.5842)
					(thickness 0.127)
				)
				(justify left)
			)
		)
		(property "Value" "36.0"
			(at -0.148158 1.3462 0)
			(unlocked yes)
			(layer "F.Fab")
			(hide yes)
			(effects
				(font
					(size 1.27 0.9652)
					(thickness 0.000001)
				)
				(justify left)
			)
		)
		(property "Device Type" "REST0125"
			(at -0.148158 1.3462 0)
			(unlocked yes)
			(layer "F.Fab")
			(hide yes)
			(effects
				(font
					(size 1.27 0.9652)
					(thickness 0.000001)
				)
				(justify left)
			)
		)
		(duplicate_pad_numbers_are_jumpers no)
		(fp_poly
			(pts
				(xy 0.635 1.0668) (xy 0.635 -1.0668) (xy -0.635 -1.0668) (xy -0.635 1.0668)
			)
			(stroke
				(width 0)
				(type default)
			)
			(fill no)
			(layer "F.CrtYd")
		)
		(fp_line
			(start -0.254 0.508)
			(end -0.254 -0.508)
			(stroke
				(width 0.0254)
				(type default)
			)
			(layer "F.Fab")
		)
		(fp_line
			(start 0.254 0.508)
			(end -0.254 0.508)
			(stroke
				(width 0.0254)
				(type default)
			)
			(layer "F.Fab")
		)
		(fp_line
			(start -0.254 -0.508)
			(end 0.254 -0.508)
			(stroke
				(width 0.0254)
				(type default)
			)
			(layer "F.Fab")
		)
		(fp_line
			(start 0.254 -0.508)
			(end 0.254 0.508)
			(stroke
				(width 0.0254)
				(type default)
			)
			(layer "F.Fab")
		)
		(pad "1" smd rect
			(at 0 -0.4191 270)
			(size 0.508 0.5334)
			(layers "F.Cu" "F.Mask" "F.Paste")
			(net "DDR0_32A_CK0_N")
		)
		(pad "2" smd rect
			(at 0 0.4191 270)
			(size 0.508 0.5334)
			(layers "F.Cu" "F.Mask" "F.Paste")
			(net "6N4748")
		)
		(zone
			(layer "F.Cu")
			(hatch none 0.5)
			(connect_pads
				(clearance 0)
			)
			(min_thickness 0.25)
			(keepout
				(tracks not_allowed)
				(vias allowed)
				(pads allowed)
				(copperpour not_allowed)
				(footprints allowed)
			)
			(placement
				(enabled no)
				(sheetname "")
			)
			(fill
				(thermal_gap 0.5)
				(thermal_bridge_width 0.5)
				(island_removal_mode 0)
			)
			(polygon
				(pts
					(xy 76.7334 28.2194) (xy 76.6826 28.2194) (xy 76.6826 28.1686) (xy 76.7334 28.1686)
				)
			)
		)
	)
	(footprint ""
		(layer "F.Cu")
		(at 81.407 23.368 -90)
		(property "Reference" "C220"
			(at 0 0 270)
			(layer "F.SilkS")
			(hide yes)
			(effects
				(font
					(size 1.27 1.27)
				)
			)
		)
		(property "Value" "1UF"
			(at -0.091846 0.2921 0)
			(unlocked yes)
			(layer "F.Fab")
			(hide yes)
			(effects
				(font
					(size 0.7874 0.5842)
					(thickness 0.2032)
				)
				(justify left)
			)
		)
		(property "Device Type" "CAPC0028"
			(at -0.091846 0.2921 0)
			(unlocked yes)
			(layer "F.Fab")
			(hide yes)
			(effects
				(font
					(size 0.7874 0.5842)
					(thickness 0.2032)
				)
				(justify left)
			)
		)
		(duplicate_pad_numbers_are_jumpers no)
		(fp_poly
			(pts
				(xy 0.635 1.0668) (xy 0.635 -1.0668) (xy -0.635 -1.0668) (xy -0.635 1.0668)
			)
			(stroke
				(width 0)
				(type default)
			)
			(fill no)
			(layer "F.CrtYd")
		)
		(fp_line
			(start -0.254 0.508)
			(end -0.254 -0.508)
			(stroke
				(width 0.0254)
				(type default)
			)
			(layer "F.Fab")
		)
		(fp_line
			(start 0.254 0.508)
			(end -0.254 0.508)
			(stroke
				(width 0.0254)
				(type default)
			)
			(layer "F.Fab")
		)
		(fp_line
			(start -0.254 -0.508)
			(end 0.254 -0.508)
			(stroke
				(width 0.0254)
				(type default)
			)
			(layer "F.Fab")
		)
		(fp_line
			(start 0.254 -0.508)
			(end 0.254 0.508)
			(stroke
				(width 0.0254)
				(type default)
			)
			(layer "F.Fab")
		)
		(pad "1" smd rect
			(at 0 -0.4191 270)
			(size 0.508 0.5334)
			(layers "F.Cu" "F.Mask" "F.Paste")
			(net "DDR_VDDQ")
		)
		(pad "2" smd rect
			(at 0 0.4191 270)
			(size 0.508 0.5334)
			(layers "F.Cu" "F.Mask" "F.Paste")
			(net "GND")
		)
		(zone
			(layer "F.Cu")
			(hatch none 0.5)
			(connect_pads
				(clearance 0)
			)
			(min_thickness 0.25)
			(keepout
				(tracks not_allowed)
				(vias allowed)
				(pads allowed)
				(copperpour not_allowed)
				(footprints allowed)
			)
			(placement
				(enabled no)
				(sheetname "")
			)
			(fill
				(thermal_gap 0.5)
				(thermal_bridge_width 0.5)
				(island_removal_mode 0)
			)
			(polygon
				(pts
					(xy 81.4324 23.3934) (xy 81.3816 23.3934) (xy 81.3816 23.3426) (xy 81.4324 23.3426)
				)
			)
		)
	)
	(footprint ""
		(layer "F.Cu")
		(at 75.8952 42.799 -90)
		(property "Reference" "TP52"
			(at -1.143 -0.15367 90)
			(unlocked yes)
			(layer "F.SilkS")
			(effects
				(font
					(size 0.7874 0.5842)
					(thickness 0.127)
				)
				(justify left)
			)
		)
		(property "Value" "*"
			(at -0.4826 -0.14732 270)
			(unlocked yes)
			(layer "F.Fab")
			(hide yes)
			(effects
				(font
					(size 1.27 0.9652)
					(thickness 0.000001)
				)
				(justify left)
			)
		)
		(property "Device Type" "TP_SMALL"
			(at -0.4826 -0.14732 270)
			(unlocked yes)
			(layer "F.Fab")
			(hide yes)
			(effects
				(font
					(size 1.27 0.9652)
					(thickness 0.000001)
				)
				(justify left)
			)
		)
		(duplicate_pad_numbers_are_jumpers no)
		(fp_line
			(start -0.8636 0.8636)
			(end 0.8636 0.8636)
			(stroke
				(width 0.1524)
				(type default)
			)
			(layer "F.SilkS")
		)
		(fp_line
			(start 0.8636 0.8636)
			(end 0.8636 -0.8636)
			(stroke
				(width 0.1524)
				(type default)
			)
			(layer "F.SilkS")
		)
		(fp_line
			(start -0.8636 -0.8636)
			(end -0.8636 0.8636)
			(stroke
				(width 0.1524)
				(type default)
			)
			(layer "F.SilkS")
		)
		(fp_line
			(start 0.8636 -0.8636)
			(end -0.8636 -0.8636)
			(stroke
				(width 0.1524)
				(type default)
			)
			(layer "F.SilkS")
		)
		(fp_poly
			(pts
				(xy -0.635 -0.635) (xy -0.635 0.635) (xy 0.635 0.635) (xy 0.635 -0.635)
			)
			(stroke
				(width 0)
				(type default)
			)
			(fill no)
			(layer "F.CrtYd")
		)
		(pad "1" smd rect
			(at 0 0 270)
			(size 1.27 1.27)
			(layers "F.Cu" "F.Mask" "F.Paste")
			(net "DDR_VTT")
		)
	)
	(footprint ""
		(layer "F.Cu")
		(at 10.033 37.592)
		(property "Reference" "C135"
			(at 1.16967 0.381 90)
			(unlocked yes)
			(layer "F.SilkS")
			(effects
				(font
					(size 0.7874 0.5842)
					(thickness 0.127)
				)
				(justify left)
			)
		)
		(property "Value" "10UF"
			(at -0.148158 1.7526 90)
			(unlocked yes)
			(layer "F.Fab")
			(hide yes)
			(effects
				(font
					(size 1.27 0.9652)
					(thickness 0.000001)
				)
				(justify left)
			)
		)
		(property "Device Type" "CAPC0058"
			(at -0.148158 1.7526 90)
			(unlocked yes)
			(layer "F.Fab")
			(hide yes)
			(effects
				(font
					(size 1.27 0.9652)
					(thickness 0.000001)
				)
				(justify left)
			)
		)
		(duplicate_pad_numbers_are_jumpers no)
		(fp_circle
			(center 0 0)
			(end 0.127 0)
			(stroke
				(width 0.2032)
				(type default)
			)
			(fill no)
			(layer "F.SilkS")
		)
		(fp_poly
			(pts
				(xy 0.7874 -1.6637) (xy -0.7874 -1.6637) (xy -0.7874 1.6637) (xy 0.7874 1.6637)
			)
			(stroke
				(width 0)
				(type default)
			)
			(fill no)
			(layer "F.CrtYd")
		)
		(fp_line
			(start -0.4064 -0.7874)
			(end 0.4064 -0.7874)
			(stroke
				(width 0.0254)
				(type default)
			)
			(layer "F.Fab")
		)
		(fp_line
			(start -0.4064 0.8128)
			(end -0.4064 -0.7874)
			(stroke
				(width 0.0254)
				(type default)
			)
			(layer "F.Fab")
		)
		(fp_line
			(start 0.4064 -0.7874)
			(end 0.4064 0.8128)
			(stroke
				(width 0.0254)
				(type default)
			)
			(layer "F.Fab")
		)
		(fp_line
			(start 0.4064 0.8128)
			(end -0.4064 0.8128)
			(stroke
				(width 0.0254)
				(type default)
			)
			(layer "F.Fab")
		)
		(pad "1" smd rect
			(at 0 -0.8001)
			(size 0.8636 0.9652)
			(layers "F.Cu" "F.Mask" "F.Paste")
			(net "VDD_5.0V")
		)
		(pad "2" smd rect
			(at 0 0.8001)
			(size 0.8636 0.9652)
			(layers "F.Cu" "F.Mask" "F.Paste")
			(net "GND")
		)
		(zone
			(layer "F.Cu")
			(hatch none 0.5)
			(connect_pads
				(clearance 0)
			)
			(min_thickness 0.25)
			(keepout
				(tracks not_allowed)
				(vias allowed)
				(pads allowed)
				(copperpour not_allowed)
				(footprints allowed)
			)
			(placement
				(enabled no)
				(sheetname "")
			)
			(fill
				(thermal_gap 0.5)
				(thermal_bridge_width 0.5)
				(island_removal_mode 0)
			)
			(polygon
				(pts
					(xy 9.9695 37.338) (xy 10.0965 37.338) (xy 10.0965 37.846) (xy 9.9695 37.846)
				)
			)
		)
	)
)
